(kicad_pcb
	(version 20260206)
	(generator "pcbnew")
	(generator_version "10.0")
	(general
		(thickness 1.6)
		(legacy_teardrops no)
	)
	(paper "A4")
	(title_block
		(title "03242023_DA0F0TMBIJ0_F0T_Motherboard_J_brd_V01_OCP.brd")
		(comment 1 "Grand Teton / footprints 3470-3477 of 6105")
	)
	(layers
		(0 "F.Cu" signal "TOP")
		(4 "In1.Cu" signal "GND")
		(6 "In2.Cu" signal "IN1")
		(8 "In3.Cu" signal "GND1")
		(10 "In4.Cu" signal "IN2")
		(12 "In5.Cu" signal "GND2")
		(14 "In6.Cu" signal "IN3")
		(16 "In7.Cu" signal "GND3")
		(18 "In8.Cu" signal "VCC")
		(20 "In9.Cu" signal "VCC1")
		(22 "In10.Cu" signal "GND4")
		(24 "In11.Cu" signal "IN4")
		(26 "In12.Cu" signal "GND5")
		(28 "In13.Cu" signal "IN5")
		(30 "In14.Cu" signal "GND6")
		(32 "In15.Cu" signal "IN6")
		(34 "In16.Cu" signal "GND7")
		(2 "B.Cu" signal "BOTTOM")
		(9 "F.Adhes" user "F.Adhesive")
		(11 "B.Adhes" user "B.Adhesive")
		(13 "F.Paste" user "Package Geometry/Pastemask Top")
		(15 "B.Paste" user "Package Geometry/Pastemask Bottom")
		(5 "F.SilkS" user "Ref Des/Silkscreen Top")
		(7 "B.SilkS" user "Ref Des/Silkscreen Bottom")
		(1 "F.Mask" user "Board Geometry/Soldermask Top")
		(3 "B.Mask" user "Board Geometry/Soldermask Bottom")
		(17 "Dwgs.User" user "User.Drawings")
		(19 "Cmts.User" user "User.Comments")
		(21 "Eco1.User" user "User.Eco1")
		(23 "Eco2.User" user "User.Eco2")
		(25 "Edge.Cuts" user "Board Geometry/Outline")
		(27 "Margin" user)
		(31 "F.CrtYd" user "Package Geometry/Place Bound Top")
		(29 "B.CrtYd" user "Package Geometry/Place Bound Bottom")
		(35 "F.Fab" user "Ref Des/Assembly Top")
		(33 "B.Fab" user "Ref Des/Assembly Bottom")
	)
	(footprint ""
		(layer "F.Cu")
		(at 193.93408 -354.904548 180)
		(property "Reference" "R629"
			(at 0 0 180)
			(layer "F.SilkS")
			(hide yes)
			(effects
				(font
					(size 1.27 1.27)
				)
			)
		)
		(property "Value" ""
			(at 0 0 180)
			(layer "F.Fab")
			(effects
				(font
					(size 1.27 1.27)
				)
			)
		)
		(duplicate_pad_numbers_are_jumpers no)
		(fp_line
			(start 0.7874 0.4064)
			(end -0.7874 0.4064)
			(stroke
				(width 0.1524)
				(type default)
			)
			(layer "F.SilkS")
		)
		(fp_line
			(start 0.7874 -0.4064)
			(end 0.7874 0.4064)
			(stroke
				(width 0.1524)
				(type default)
			)
			(layer "F.SilkS")
		)
		(fp_line
			(start -0.7874 0.4064)
			(end -0.7874 -0.4064)
			(stroke
				(width 0.1524)
				(type default)
			)
			(layer "F.SilkS")
		)
		(fp_line
			(start -0.7874 -0.4064)
			(end 0.7874 -0.4064)
			(stroke
				(width 0.1524)
				(type default)
			)
			(layer "F.SilkS")
		)
		(fp_line
			(start 0.67945 0.3048)
			(end 0.120396 0.3048)
			(stroke
				(width 0.1)
				(type default)
			)
			(layer "F.Fab")
		)
		(fp_line
			(start 0.67945 -0.3048)
			(end 0.67945 0.3048)
			(stroke
				(width 0.1)
				(type default)
			)
			(layer "F.Fab")
		)
		(fp_line
			(start 0.12065 -0.2794)
			(end 0.12065 -0.3048)
			(stroke
				(width 0.1)
				(type default)
			)
			(layer "F.Fab")
		)
		(fp_line
			(start 0.12065 -0.3048)
			(end 0.67945 -0.3048)
			(stroke
				(width 0.1)
				(type default)
			)
			(layer "F.Fab")
		)
		(fp_line
			(start 0.120396 0.3048)
			(end 0.120396 0.2794)
			(stroke
				(width 0.1)
				(type default)
			)
			(layer "F.Fab")
		)
		(fp_line
			(start 0.120396 0.2794)
			(end -0.12065 0.2794)
			(stroke
				(width 0.1)
				(type default)
			)
			(layer "F.Fab")
		)
		(fp_line
			(start -0.12065 0.3048)
			(end -0.67945 0.3048)
			(stroke
				(width 0.1)
				(type default)
			)
			(layer "F.Fab")
		)
		(fp_line
			(start -0.12065 0.2794)
			(end -0.12065 0.3048)
			(stroke
				(width 0.1)
				(type default)
			)
			(layer "F.Fab")
		)
		(fp_line
			(start -0.12065 -0.2794)
			(end 0.12065 -0.2794)
			(stroke
				(width 0.1)
				(type default)
			)
			(layer "F.Fab")
		)
		(fp_line
			(start -0.12065 -0.305054)
			(end -0.12065 -0.2794)
			(stroke
				(width 0.1)
				(type default)
			)
			(layer "F.Fab")
		)
		(fp_line
			(start -0.67945 0.3048)
			(end -0.67945 -0.305054)
			(stroke
				(width 0.1)
				(type default)
			)
			(layer "F.Fab")
		)
		(fp_line
			(start -0.67945 -0.305054)
			(end -0.12065 -0.305054)
			(stroke
				(width 0.1)
				(type default)
			)
			(layer "F.Fab")
		)
		(pad "1" smd circle
			(at -0.40005 0 180)
			(size 0 0)
			(layers "F.Cu" "F.Mask" "F.Paste")
			(net "P3V3_AUX")
		)
		(pad "2" smd circle
			(at 0.40005 0 180)
			(size 0 0)
			(layers "F.Cu" "F.Mask" "F.Paste")
			(net "PU_PIROM_CPU1_ADDR0")
		)
	)
	(footprint ""
		(layer "F.Cu")
		(at 431.433478 -364.574328)
		(property "Reference" "PC1674"
			(at 0 0 0)
			(layer "F.SilkS")
			(hide yes)
			(effects
				(font
					(size 1.27 1.27)
				)
			)
		)
		(property "Value" ""
			(at 0 0 0)
			(layer "F.Fab")
			(effects
				(font
					(size 1.27 1.27)
				)
			)
		)
		(duplicate_pad_numbers_are_jumpers no)
		(fp_line
			(start -1.524 -0.762)
			(end 1.524 -0.762)
			(stroke
				(width 0.1524)
				(type default)
			)
			(layer "F.SilkS")
		)
		(fp_line
			(start -1.524 0.762)
			(end -1.524 -0.762)
			(stroke
				(width 0.1524)
				(type default)
			)
			(layer "F.SilkS")
		)
		(fp_line
			(start 1.524 -0.762)
			(end 1.524 0.762)
			(stroke
				(width 0.1524)
				(type default)
			)
			(layer "F.SilkS")
		)
		(fp_line
			(start 1.524 0.762)
			(end -1.524 0.762)
			(stroke
				(width 0.1524)
				(type default)
			)
			(layer "F.SilkS")
		)
		(fp_line
			(start -1.1049 -0.724916)
			(end -1.1049 0.724916)
			(stroke
				(width 0.1)
				(type default)
			)
			(layer "F.Fab")
		)
		(fp_line
			(start -1.1049 0.724916)
			(end 1.1049 0.724916)
			(stroke
				(width 0.1)
				(type default)
			)
			(layer "F.Fab")
		)
		(fp_line
			(start 1.1049 -0.724916)
			(end -1.1049 -0.724916)
			(stroke
				(width 0.1)
				(type default)
			)
			(layer "F.Fab")
		)
		(fp_line
			(start 1.1049 0.724916)
			(end 1.1049 -0.724916)
			(stroke
				(width 0.1)
				(type default)
			)
			(layer "F.Fab")
		)
		(pad "1" smd rect
			(at -0.889 0 180)
			(size 1.016 1.27)
			(layers "F.Cu" "F.Mask" "F.Paste")
			(net "SW_P12V_PVCCFA_EHV_FIVRA_CPU0_R")
		)
		(pad "2" smd rect
			(at 0.889 0 180)
			(size 1.016 1.27)
			(layers "F.Cu" "F.Mask" "F.Paste")
			(net "GND")
		)
	)
	(footprint ""
		(layer "F.Cu")
		(at 28.081732 -416.016948)
		(property "Reference" "Q72"
			(at 0.2286 -1.918208 0)
			(unlocked yes)
			(layer "F.SilkS")
			(effects
				(font
					(size 0.7874 0.5842)
					(thickness 0.1524)
				)
				(justify left)
			)
		)
		(property "Value" ""
			(at 0 0 0)
			(layer "F.Fab")
			(effects
				(font
					(size 1.27 1.27)
				)
			)
		)
		(duplicate_pad_numbers_are_jumpers no)
		(fp_line
			(start -1.332738 -1.100074)
			(end -0.4826 -1.100074)
			(stroke
				(width 0.1524)
				(type default)
			)
			(layer "F.SilkS")
		)
		(fp_line
			(start -1.332738 1.100074)
			(end -1.332738 -1.100074)
			(stroke
				(width 0.1524)
				(type default)
			)
			(layer "F.SilkS")
		)
		(fp_line
			(start -0.4826 -1.100074)
			(end 0 -0.541274)
			(stroke
				(width 0.1524)
				(type default)
			)
			(layer "F.SilkS")
		)
		(fp_line
			(start 0 -0.541274)
			(end 0.4826 -1.100074)
			(stroke
				(width 0.1524)
				(type default)
			)
			(layer "F.SilkS")
		)
		(fp_line
			(start 0.4826 -1.100074)
			(end 1.332738 -1.100074)
			(stroke
				(width 0.1524)
				(type default)
			)
			(layer "F.SilkS")
		)
		(fp_line
			(start 1.332738 -1.100074)
			(end 1.332738 1.100074)
			(stroke
				(width 0.1524)
				(type default)
			)
			(layer "F.SilkS")
		)
		(fp_line
			(start 1.332738 1.100074)
			(end -1.332738 1.100074)
			(stroke
				(width 0.1524)
				(type default)
			)
			(layer "F.SilkS")
		)
		(fp_poly
			(pts
				(xy -0.94996 -1.23317) (xy -1.300988 -1.935226) (xy -0.598932 -1.935226)
			)
			(stroke
				(width 0)
				(type default)
			)
			(fill yes)
			(layer "F.SilkS")
		)
		(fp_line
			(start -0.674878 -1.100074)
			(end 0.674878 -1.100074)
			(stroke
				(width 0.1)
				(type default)
			)
			(layer "F.Fab")
		)
		(fp_line
			(start -0.674878 1.100074)
			(end -0.674878 -1.100074)
			(stroke
				(width 0.1)
				(type default)
			)
			(layer "F.Fab")
		)
		(fp_line
			(start 0.674878 -1.100074)
			(end 0.674878 1.100074)
			(stroke
				(width 0.1)
				(type default)
			)
			(layer "F.Fab")
		)
		(fp_line
			(start 0.674878 1.100074)
			(end -0.674878 1.100074)
			(stroke
				(width 0.1)
				(type default)
			)
			(layer "F.Fab")
		)
		(fp_poly
			(pts
				(xy -2.2352 -0.298958) (xy -2.2352 -1.001014) (xy -1.533144 -0.649986)
			)
			(stroke
				(width 0)
				(type default)
			)
			(fill yes)
			(layer "F.Fab")
		)
		(pad "1" smd rect
			(at -0.94996 -0.649986 90)
			(size 0.4318 0.508)
			(layers "F.Cu" "F.Mask" "F.Paste")
			(net "GND")
		)
		(pad "2" smd rect
			(at -0.94996 0 90)
			(size 0.4318 0.508)
			(layers "F.Cu" "F.Mask" "F.Paste")
			(net "FM_GPU_PWRGD")
		)
		(pad "3" smd rect
			(at -0.94996 0.649986 90)
			(size 0.4318 0.508)
			(layers "F.Cu" "F.Mask" "F.Paste")
			(net "FM_GPU_PWRGD_ISO")
		)
		(pad "4" smd rect
			(at 0.94996 0.649986 90)
			(size 0.4318 0.508)
			(layers "F.Cu" "F.Mask" "F.Paste")
			(net "GND")
		)
		(pad "5" smd rect
			(at 0.94996 0 90)
			(size 0.4318 0.508)
			(layers "F.Cu" "F.Mask" "F.Paste")
			(net "FM_GPU_PWRGD_N")
		)
		(pad "6" smd rect
			(at 0.94996 -0.649986 90)
			(size 0.4318 0.508)
			(layers "F.Cu" "F.Mask" "F.Paste")
			(net "FM_GPU_PWRGD_N")
		)
	)
	(footprint ""
		(layer "F.Cu")
		(at 422.273984 -361.896914 -90)
		(property "Reference" "PC1213_P0_3"
			(at 0 0 270)
			(layer "F.SilkS")
			(hide yes)
			(effects
				(font
					(size 1.27 1.27)
				)
			)
		)
		(property "Value" ""
			(at 0 0 270)
			(layer "F.Fab")
			(effects
				(font
					(size 1.27 1.27)
				)
			)
		)
		(duplicate_pad_numbers_are_jumpers no)
		(fp_line
			(start -0.7874 0.4064)
			(end -0.7874 -0.4064)
			(stroke
				(width 0.1524)
				(type default)
			)
			(layer "F.SilkS")
		)
		(fp_line
			(start 0.7874 0.4064)
			(end -0.7874 0.4064)
			(stroke
				(width 0.1524)
				(type default)
			)
			(layer "F.SilkS")
		)
		(fp_line
			(start -0.7874 -0.4064)
			(end 0.7874 -0.4064)
			(stroke
				(width 0.1524)
				(type default)
			)
			(layer "F.SilkS")
		)
		(fp_line
			(start 0.7874 -0.4064)
			(end 0.7874 0.4064)
			(stroke
				(width 0.1524)
				(type default)
			)
			(layer "F.SilkS")
		)
		(fp_line
			(start -0.67945 0.3048)
			(end -0.67945 -0.305054)
			(stroke
				(width 0.1)
				(type default)
			)
			(layer "F.Fab")
		)
		(fp_line
			(start -0.12065 0.3048)
			(end -0.67945 0.3048)
			(stroke
				(width 0.1)
				(type default)
			)
			(layer "F.Fab")
		)
		(fp_line
			(start 0.120396 0.3048)
			(end 0.120396 0.2794)
			(stroke
				(width 0.1)
				(type default)
			)
			(layer "F.Fab")
		)
		(fp_line
			(start 0.67945 0.3048)
			(end 0.120396 0.3048)
			(stroke
				(width 0.1)
				(type default)
			)
			(layer "F.Fab")
		)
		(fp_line
			(start -0.12065 0.2794)
			(end -0.12065 0.3048)
			(stroke
				(width 0.1)
				(type default)
			)
			(layer "F.Fab")
		)
		(fp_line
			(start 0.120396 0.2794)
			(end -0.12065 0.2794)
			(stroke
				(width 0.1)
				(type default)
			)
			(layer "F.Fab")
		)
		(fp_line
			(start -0.12065 -0.2794)
			(end 0.12065 -0.2794)
			(stroke
				(width 0.1)
				(type default)
			)
			(layer "F.Fab")
		)
		(fp_line
			(start 0.12065 -0.2794)
			(end 0.12065 -0.3048)
			(stroke
				(width 0.1)
				(type default)
			)
			(layer "F.Fab")
		)
		(fp_line
			(start 0.12065 -0.3048)
			(end 0.67945 -0.3048)
			(stroke
				(width 0.1)
				(type default)
			)
			(layer "F.Fab")
		)
		(fp_line
			(start 0.67945 -0.3048)
			(end 0.67945 0.3048)
			(stroke
				(width 0.1)
				(type default)
			)
			(layer "F.Fab")
		)
		(fp_line
			(start -0.67945 -0.305054)
			(end -0.12065 -0.305054)
			(stroke
				(width 0.1)
				(type default)
			)
			(layer "F.Fab")
		)
		(fp_line
			(start -0.12065 -0.305054)
			(end -0.12065 -0.2794)
			(stroke
				(width 0.1)
				(type default)
			)
			(layer "F.Fab")
		)
		(pad "1" smd circle
			(at -0.40005 0 270)
			(size 0 0)
			(layers "F.Cu" "F.Mask" "F.Paste")
			(net "PVCCFA_EHV_FIVRA_CPU0_PVCC1")
		)
		(pad "2" smd circle
			(at 0.40005 0 270)
			(size 0 0)
			(layers "F.Cu" "F.Mask" "F.Paste")
			(net "GND")
		)
	)
	(footprint ""
		(layer "F.Cu")
		(at 383.65049 -402.371052 -90)
		(property "Reference" "C943"
			(at 0 0 270)
			(layer "F.SilkS")
			(hide yes)
			(effects
				(font
					(size 1.27 1.27)
				)
			)
		)
		(property "Value" ""
			(at 0 0 270)
			(layer "F.Fab")
			(effects
				(font
					(size 1.27 1.27)
				)
			)
		)
		(duplicate_pad_numbers_are_jumpers no)
		(fp_line
			(start -0.299974 0.150114)
			(end -0.299974 -0.150114)
			(stroke
				(width 0.1)
				(type default)
			)
			(layer "F.Fab")
		)
		(fp_line
			(start 0.299974 0.150114)
			(end -0.299974 0.150114)
			(stroke
				(width 0.1)
				(type default)
			)
			(layer "F.Fab")
		)
		(fp_line
			(start -0.299974 -0.150114)
			(end 0.299974 -0.150114)
			(stroke
				(width 0.1)
				(type default)
			)
			(layer "F.Fab")
		)
		(fp_line
			(start 0.299974 -0.150114)
			(end 0.299974 0.150114)
			(stroke
				(width 0.1)
				(type default)
			)
			(layer "F.Fab")
		)
		(pad "1" smd rect
			(at -0.2667 0 270)
			(size 0.3048 0.381)
			(layers "F.Cu" "F.Mask" "F.Paste")
			(net "P5E_CPU0_PE2_TX_C_DP<11>")
		)
		(pad "2" smd rect
			(at 0.2667 0 270)
			(size 0.3048 0.381)
			(layers "F.Cu" "F.Mask" "F.Paste")
			(net "P5E_CPU0_PE2_TX_DP<11>")
		)
	)
	(footprint ""
		(layer "F.Cu")
		(at 143.832834 -408.517344 -90)
		(property "Reference" "C1531"
			(at 0 0 270)
			(layer "F.SilkS")
			(hide yes)
			(effects
				(font
					(size 1.27 1.27)
				)
			)
		)
		(property "Value" ""
			(at 0 0 270)
			(layer "F.Fab")
			(effects
				(font
					(size 1.27 1.27)
				)
			)
		)
		(duplicate_pad_numbers_are_jumpers no)
		(fp_line
			(start -0.299974 0.150114)
			(end -0.299974 -0.150114)
			(stroke
				(width 0.1)
				(type default)
			)
			(layer "F.Fab")
		)
		(fp_line
			(start 0.299974 0.150114)
			(end -0.299974 0.150114)
			(stroke
				(width 0.1)
				(type default)
			)
			(layer "F.Fab")
		)
		(fp_line
			(start -0.299974 -0.150114)
			(end 0.299974 -0.150114)
			(stroke
				(width 0.1)
				(type default)
			)
			(layer "F.Fab")
		)
		(fp_line
			(start 0.299974 -0.150114)
			(end 0.299974 0.150114)
			(stroke
				(width 0.1)
				(type default)
			)
			(layer "F.Fab")
		)
		(pad "1" smd rect
			(at -0.2667 0 270)
			(size 0.3048 0.381)
			(layers "F.Cu" "F.Mask" "F.Paste")
			(net "P5E_CPU1_PE3_TX_C_DP<8>")
		)
		(pad "2" smd rect
			(at 0.2667 0 270)
			(size 0.3048 0.381)
			(layers "F.Cu" "F.Mask" "F.Paste")
			(net "P5E_CPU1_PE3_TX_DP<8>")
		)
	)
	(footprint ""
		(layer "F.Cu")
		(at 366.06988 -294.01008 180)
		(property "Reference" "C220"
			(at 0 0 180)
			(layer "F.SilkS")
			(hide yes)
			(effects
				(font
					(size 1.27 1.27)
				)
			)
		)
		(property "Value" ""
			(at 0 0 180)
			(layer "F.Fab")
			(effects
				(font
					(size 1.27 1.27)
				)
			)
		)
		(duplicate_pad_numbers_are_jumpers no)
		(fp_line
			(start 1.524 0.762)
			(end -1.524 0.762)
			(stroke
				(width 0.1524)
				(type default)
			)
			(layer "F.SilkS")
		)
		(fp_line
			(start 1.524 -0.762)
			(end 1.524 0.762)
			(stroke
				(width 0.1524)
				(type default)
			)
			(layer "F.SilkS")
		)
		(fp_line
			(start -1.524 0.762)
			(end -1.524 -0.762)
			(stroke
				(width 0.1524)
				(type default)
			)
			(layer "F.SilkS")
		)
		(fp_line
			(start -1.524 -0.762)
			(end 1.524 -0.762)
			(stroke
				(width 0.1524)
				(type default)
			)
			(layer "F.SilkS")
		)
		(fp_line
			(start 1.1049 0.724916)
			(end 1.1049 -0.724916)
			(stroke
				(width 0.1)
				(type default)
			)
			(layer "F.Fab")
		)
		(fp_line
			(start 1.1049 -0.724916)
			(end -1.1049 -0.724916)
			(stroke
				(width 0.1)
				(type default)
			)
			(layer "F.Fab")
		)
		(fp_line
			(start -1.1049 0.724916)
			(end 1.1049 0.724916)
			(stroke
				(width 0.1)
				(type default)
			)
			(layer "F.Fab")
		)
		(fp_line
			(start -1.1049 -0.724916)
			(end -1.1049 0.724916)
			(stroke
				(width 0.1)
				(type default)
			)
			(layer "F.Fab")
		)
		(pad "1" smd rect
			(at -0.889 0)
			(size 1.016 1.27)
			(layers "F.Cu" "F.Mask" "F.Paste")
			(net "PVCCIN_CPU0")
		)
		(pad "2" smd rect
			(at 0.889 0)
			(size 1.016 1.27)
			(layers "F.Cu" "F.Mask" "F.Paste")
			(net "GND")
		)
	)
	(footprint ""
		(layer "F.Cu")
		(at 120.269 -60.035948 90)
		(property "Reference" "R4623"
			(at 0 0 90)
			(layer "F.SilkS")
			(hide yes)
			(effects
				(font
					(size 1.27 1.27)
				)
			)
		)
		(property "Value" ""
			(at 0 0 90)
			(layer "F.Fab")
			(effects
				(font
					(size 1.27 1.27)
				)
			)
		)
		(duplicate_pad_numbers_are_jumpers no)
		(fp_line
			(start 0.7874 -0.4064)
			(end 0.7874 0.4064)
			(stroke
				(width 0.1524)
				(type default)
			)
			(layer "F.SilkS")
		)
		(fp_line
			(start -0.7874 -0.4064)
			(end 0.7874 -0.4064)
			(stroke
				(width 0.1524)
				(type default)
			)
			(layer "F.SilkS")
		)
		(fp_line
			(start 0.7874 0.4064)
			(end -0.7874 0.4064)
			(stroke
				(width 0.1524)
				(type default)
			)
			(layer "F.SilkS")
		)
		(fp_line
			(start -0.7874 0.4064)
			(end -0.7874 -0.4064)
			(stroke
				(width 0.1524)
				(type default)
			)
			(layer "F.SilkS")
		)
		(fp_line
			(start -0.12065 -0.305054)
			(end -0.12065 -0.2794)
			(stroke
				(width 0.1)
				(type default)
			)
			(layer "F.Fab")
		)
		(fp_line
			(start -0.67945 -0.305054)
			(end -0.12065 -0.305054)
			(stroke
				(width 0.1)
				(type default)
			)
			(layer "F.Fab")
		)
		(fp_line
			(start 0.67945 -0.3048)
			(end 0.67945 0.3048)
			(stroke
				(width 0.1)
				(type default)
			)
			(layer "F.Fab")
		)
		(fp_line
			(start 0.12065 -0.3048)
			(end 0.67945 -0.3048)
			(stroke
				(width 0.1)
				(type default)
			)
			(layer "F.Fab")
		)
		(fp_line
			(start 0.12065 -0.2794)
			(end 0.12065 -0.3048)
			(stroke
				(width 0.1)
				(type default)
			)
			(layer "F.Fab")
		)
		(fp_line
			(start -0.12065 -0.2794)
			(end 0.12065 -0.2794)
			(stroke
				(width 0.1)
				(type default)
			)
			(layer "F.Fab")
		)
		(fp_line
			(start 0.120396 0.2794)
			(end -0.12065 0.2794)
			(stroke
				(width 0.1)
				(type default)
			)
			(layer "F.Fab")
		)
		(fp_line
			(start -0.12065 0.2794)
			(end -0.12065 0.3048)
			(stroke
				(width 0.1)
				(type default)
			)
			(layer "F.Fab")
		)
		(fp_line
			(start 0.67945 0.3048)
			(end 0.120396 0.3048)
			(stroke
				(width 0.1)
				(type default)
			)
			(layer "F.Fab")
		)
		(fp_line
			(start 0.120396 0.3048)
			(end 0.120396 0.2794)
			(stroke
				(width 0.1)
				(type default)
			)
			(layer "F.Fab")
		)
		(fp_line
			(start -0.12065 0.3048)
			(end -0.67945 0.3048)
			(stroke
				(width 0.1)
				(type default)
			)
			(layer "F.Fab")
		)
		(fp_line
			(start -0.67945 0.3048)
			(end -0.67945 -0.305054)
			(stroke
				(width 0.1)
				(type default)
			)
			(layer "F.Fab")
		)
		(pad "1" smd circle
			(at -0.40005 0 90)
			(size 0 0)
			(layers "F.Cu" "F.Mask" "F.Paste")
			(net "P3V3_AUX")
		)
		(pad "2" smd circle
			(at 0.40005 0 90)
			(size 0 0)
			(layers "F.Cu" "F.Mask" "F.Paste")
			(net "PU_JTAG_SW_PU")
		)
	)
)
